# T6G (Grand Teton) — schematic netlist excerpt (pin names and nets, part order shuffled) for the footprints in the layout excerpt that follows; sources: Cadence DE-HDL packaged netlist, KiCad conversion of 04192023_DAF0TMB3IC0_F0TG_MB_C_brd_V02_OCP.brd

D74  Q_LED  IC  pkg SMLF  page 255 : A = LED_PWRGD_PVDDCR_CPU0_P0_R ; C = LED_PWRGD_PVDDCR_CPU0_P0_D
H86  HOLE  EMPTY  pkg TH  page 230 : \1\ = GND
R1746  Q_RES  10K 1% CHIP  pkg 0402LF  page 171 : A = P3V3_AUX ; B = JTAG_SCM_MUX_TMS

(kicad_pcb
	(version 20260206)
	(generator "pcbnew")
	(generator_version "10.0")
	(general
		(thickness 1.6)
		(legacy_teardrops no)
	)
	(paper "A4")
	(title_block
		(title "04192023_DAF0TMB3IC0_F0TG_MB_C_brd_V02_OCP.brd")
		(comment 1 "Grand Teton / footprints 1973-1975 of 8354")
	)
	(layers
		(0 "F.Cu" signal "TOP")
		(4 "In1.Cu" signal "GND")
		(6 "In2.Cu" signal "IN1")
		(8 "In3.Cu" signal "GND1")
		(10 "In4.Cu" signal "IN2")
		(12 "In5.Cu" signal "GND2")
		(14 "In6.Cu" signal "IN3")
		(16 "In7.Cu" signal "GND3")
		(18 "In8.Cu" signal "VCC")
		(20 "In9.Cu" signal "VCC1")
		(22 "In10.Cu" signal "GND4")
		(24 "In11.Cu" signal "IN4")
		(26 "In12.Cu" signal "GND5")
		(28 "In13.Cu" signal "IN5")
		(30 "In14.Cu" signal "GND6")
		(32 "In15.Cu" signal "IN6")
		(34 "In16.Cu" signal "GND7")
		(2 "B.Cu" signal "BOTTOM")
		(9 "F.Adhes" user "F.Adhesive")
		(11 "B.Adhes" user "B.Adhesive")
		(13 "F.Paste" user "Package Geometry/Pastemask Top")
		(15 "B.Paste" user "Package Geometry/Pastemask Bottom")
		(5 "F.SilkS" user "Ref Des/Silkscreen Top")
		(7 "B.SilkS" user "Ref Des/Silkscreen Bottom")
		(1 "F.Mask" user "Board Geometry/Soldermask Top")
		(3 "B.Mask" user "Board Geometry/Soldermask Bottom")
		(17 "Dwgs.User" user "User.Drawings")
		(19 "Cmts.User" user "User.Comments")
		(21 "Eco1.User" user "User.Eco1")
		(23 "Eco2.User" user "User.Eco2")
		(25 "Edge.Cuts" user "Board Geometry/Outline")
		(27 "Margin" user)
		(31 "F.CrtYd" user "Package Geometry/Place Bound Top")
		(29 "B.CrtYd" user "Package Geometry/Place Bound Bottom")
		(35 "F.Fab" user "Ref Des/Assembly Top")
		(33 "B.Fab" user "Ref Des/Assembly Bottom")
	)
	(footprint ""
		(layer "F.Cu")
		(at 324.635876 -70.098412 90)
		(property "Reference" "D74"
			(at -3.934714 -0.691642 90)
			(unlocked yes)
			(layer "F.SilkS")
			(effects
				(font
					(size 0.7874 0.5842)
					(thickness 0.1524)
				)
				(justify left)
			)
		)
		(property "Value" ""
			(at 0 0 90)
			(layer "F.Fab")
			(effects
				(font
					(size 1.27 1.27)
				)
			)
		)
		(duplicate_pad_numbers_are_jumpers no)
		(fp_line
			(start 1.16078 -0.4826)
			(end 1.16078 0.4826)
			(stroke
				(width 0.1524)
				(type default)
			)
			(layer "F.SilkS")
		)
		(fp_line
			(start 1.03378 -0.4826)
			(end 1.03378 0.4826)
			(stroke
				(width 0.1524)
				(type default)
			)
			(layer "F.SilkS")
		)
		(fp_line
			(start 0.90678 -0.4826)
			(end 0.90678 0.4826)
			(stroke
				(width 0.1524)
				(type default)
			)
			(layer "F.SilkS")
		)
		(fp_line
			(start -0.64008 -0.4826)
			(end 1.16078 -0.4826)
			(stroke
				(width 0.1524)
				(type default)
			)
			(layer "F.SilkS")
		)
		(fp_line
			(start -0.79248 -0.4826)
			(end 1.03378 -0.4826)
			(stroke
				(width 0.1524)
				(type default)
			)
			(layer "F.SilkS")
		)
		(fp_line
			(start -0.89408 -0.4826)
			(end 0.90678 -0.4826)
			(stroke
				(width 0.1524)
				(type default)
			)
			(layer "F.SilkS")
		)
		(fp_line
			(start 1.16078 0.4826)
			(end -0.64008 0.4826)
			(stroke
				(width 0.1524)
				(type default)
			)
			(layer "F.SilkS")
		)
		(fp_line
			(start 1.03378 0.4826)
			(end -0.79248 0.4826)
			(stroke
				(width 0.1524)
				(type default)
			)
			(layer "F.SilkS")
		)
		(fp_line
			(start 0.90678 0.4826)
			(end -0.90678 0.4826)
			(stroke
				(width 0.1524)
				(type default)
			)
			(layer "F.SilkS")
		)
		(fp_line
			(start -0.90678 0.4826)
			(end -0.90678 -0.4699)
			(stroke
				(width 0.1524)
				(type default)
			)
			(layer "F.SilkS")
		)
		(fp_line
			(start 0.499872 -0.249936)
			(end 0.499872 0.249936)
			(stroke
				(width 0.1)
				(type default)
			)
			(layer "F.Fab")
		)
		(fp_line
			(start -0.499872 -0.249936)
			(end 0.499872 -0.249936)
			(stroke
				(width 0.1)
				(type default)
			)
			(layer "F.Fab")
		)
		(fp_line
			(start 0.499872 0.249936)
			(end -0.499872 0.249936)
			(stroke
				(width 0.1)
				(type default)
			)
			(layer "F.Fab")
		)
		(fp_line
			(start -0.499872 0.249936)
			(end -0.499872 -0.249936)
			(stroke
				(width 0.1)
				(type default)
			)
			(layer "F.Fab")
		)
		(pad "A" smd rect
			(at -0.47498 0 90)
			(size 0.6096 0.7112)
			(layers "F.Cu" "F.Mask" "F.Paste")
			(net "LED_PWRGD_PVDDCR_CPU0_P0_R")
		)
		(pad "C" smd rect
			(at 0.47498 0 90)
			(size 0.6096 0.7112)
			(layers "F.Cu" "F.Mask" "F.Paste")
			(net "LED_PWRGD_PVDDCR_CPU0_P0_D")
		)
	)
	(footprint ""
		(layer "F.Cu")
		(at 265.649964 -22.29993)
		(property "Reference" "H86"
			(at -4.919472 -5.971794 0)
			(unlocked yes)
			(layer "F.SilkS")
			(effects
				(font
					(size 0.7874 0.5842)
					(thickness 0.1524)
				)
				(justify left)
			)
		)
		(property "Value" ""
			(at 0 0 0)
			(layer "F.Fab")
			(effects
				(font
					(size 1.27 1.27)
				)
			)
		)
		(duplicate_pad_numbers_are_jumpers no)
		(pad "1" thru_hole circle
			(at 0 0)
			(size 10.0076 10.0076)
			(drill 5.6134)
			(layers "*.Cu" "*.Mask")
			(remove_unused_layers no)
			(net "GND")
			(clearance -1.9431)
		)
	)
	(footprint ""
		(layer "F.Cu")
		(at 105.64876 -57.486042 180)
		(property "Reference" "R1746"
			(at 0 0 180)
			(layer "F.SilkS")
			(hide yes)
			(effects
				(font
					(size 1.27 1.27)
				)
			)
		)
		(property "Value" ""
			(at 0 0 180)
			(layer "F.Fab")
			(effects
				(font
					(size 1.27 1.27)
				)
			)
		)
		(duplicate_pad_numbers_are_jumpers no)
		(fp_line
			(start 0.7874 0.4064)
			(end -0.7874 0.4064)
			(stroke
				(width 0.1524)
				(type default)
			)
			(layer "F.SilkS")
		)
		(fp_line
			(start 0.7874 -0.4064)
			(end 0.7874 0.4064)
			(stroke
				(width 0.1524)
				(type default)
			)
			(layer "F.SilkS")
		)
		(fp_line
			(start -0.7874 0.4064)
			(end -0.7874 -0.4064)
			(stroke
				(width 0.1524)
				(type default)
			)
			(layer "F.SilkS")
		)
		(fp_line
			(start -0.7874 -0.4064)
			(end 0.7874 -0.4064)
			(stroke
				(width 0.1524)
				(type default)
			)
			(layer "F.SilkS")
		)
		(fp_line
			(start 0.67945 0.3048)
			(end 0.120396 0.3048)
			(stroke
				(width 0.1)
				(type default)
			)
			(layer "F.Fab")
		)
		(fp_line
			(start 0.67945 -0.3048)
			(end 0.67945 0.3048)
			(stroke
				(width 0.1)
				(type default)
			)
			(layer "F.Fab")
		)
		(fp_line
			(start 0.12065 -0.2794)
			(end 0.12065 -0.3048)
			(stroke
				(width 0.1)
				(type default)
			)
			(layer "F.Fab")
		)
		(fp_line
			(start 0.12065 -0.3048)
			(end 0.67945 -0.3048)
			(stroke
				(width 0.1)
				(type default)
			)
			(layer "F.Fab")
		)
		(fp_line
			(start 0.120396 0.3048)
			(end 0.120396 0.2794)
			(stroke
				(width 0.1)
				(type default)
			)
			(layer "F.Fab")
		)
		(fp_line
			(start 0.120396 0.2794)
			(end -0.12065 0.2794)
			(stroke
				(width 0.1)
				(type default)
			)
			(layer "F.Fab")
		)
		(fp_line
			(start -0.12065 0.3048)
			(end -0.67945 0.3048)
			(stroke
				(width 0.1)
				(type default)
			)
			(layer "F.Fab")
		)
		(fp_line
			(start -0.12065 0.2794)
			(end -0.12065 0.3048)
			(stroke
				(width 0.1)
				(type default)
			)
			(layer "F.Fab")
		)
		(fp_line
			(start -0.12065 -0.2794)
			(end 0.12065 -0.2794)
			(stroke
				(width 0.1)
				(type default)
			)
			(layer "F.Fab")
		)
		(fp_line
			(start -0.12065 -0.305054)
			(end -0.12065 -0.2794)
			(stroke
				(width 0.1)
				(type default)
			)
			(layer "F.Fab")
		)
		(fp_line
			(start -0.67945 0.3048)
			(end -0.67945 -0.305054)
			(stroke
				(width 0.1)
				(type default)
			)
			(layer "F.Fab")
		)
		(fp_line
			(start -0.67945 -0.305054)
			(end -0.12065 -0.305054)
			(stroke
				(width 0.1)
				(type default)
			)
			(layer "F.Fab")
		)
		(pad "1" smd circle
			(at -0.40005 0 180)
			(size 0 0)
			(layers "F.Cu" "F.Mask" "F.Paste")
			(net "P3V3_AUX")
		)
		(pad "2" smd circle
			(at 0.40005 0 180)
			(size 0 0)
			(layers "F.Cu" "F.Mask" "F.Paste")
			(net "JTAG_SCM_MUX_TMS")
		)
	)
)
